# T6G (Grand Teton) — schematic netlist excerpt (pin names and nets, part order shuffled) for the footprints in the layout excerpt that follows; sources: Cadence DE-HDL packaged netlist, KiCad conversion of 04192023_DAF0TMB3IC0_F0TG_MB_C_brd_V02_OCP.brd

PR3  Q_RES  10K 1% CHIP  pkg 0402LF  page 207 : A = PVDD11_S3_P0_VMON ; B = GND
R452  Q_RES  4.7K 5% CHIP  pkg 0402LF  page 28 : A = CPU0_NV_SAVE_N ; B = PVDD18_S5_P0

(kicad_pcb
	(version 20260206)
	(generator "pcbnew")
	(generator_version "10.0")
	(general
		(thickness 1.6)
		(legacy_teardrops no)
	)
	(paper "A4")
	(title_block
		(title "04192023_DAF0TMB3IC0_F0TG_MB_C_brd_V02_OCP.brd")
		(comment 1 "Grand Teton / footprints 7526-7527 of 8354")
	)
	(layers
		(0 "F.Cu" signal "TOP")
		(4 "In1.Cu" signal "GND")
		(6 "In2.Cu" signal "IN1")
		(8 "In3.Cu" signal "GND1")
		(10 "In4.Cu" signal "IN2")
		(12 "In5.Cu" signal "GND2")
		(14 "In6.Cu" signal "IN3")
		(16 "In7.Cu" signal "GND3")
		(18 "In8.Cu" signal "VCC")
		(20 "In9.Cu" signal "VCC1")
		(22 "In10.Cu" signal "GND4")
		(24 "In11.Cu" signal "IN4")
		(26 "In12.Cu" signal "GND5")
		(28 "In13.Cu" signal "IN5")
		(30 "In14.Cu" signal "GND6")
		(32 "In15.Cu" signal "IN6")
		(34 "In16.Cu" signal "GND7")
		(2 "B.Cu" signal "BOTTOM")
		(9 "F.Adhes" user "F.Adhesive")
		(11 "B.Adhes" user "B.Adhesive")
		(13 "F.Paste" user "Package Geometry/Pastemask Top")
		(15 "B.Paste" user "Package Geometry/Pastemask Bottom")
		(5 "F.SilkS" user "Ref Des/Silkscreen Top")
		(7 "B.SilkS" user "Ref Des/Silkscreen Bottom")
		(1 "F.Mask" user "Board Geometry/Soldermask Top")
		(3 "B.Mask" user "Board Geometry/Soldermask Bottom")
		(17 "Dwgs.User" user "User.Drawings")
		(19 "Cmts.User" user "User.Comments")
		(21 "Eco1.User" user "User.Eco1")
		(23 "Eco2.User" user "User.Eco2")
		(25 "Edge.Cuts" user "Board Geometry/Outline")
		(27 "Margin" user)
		(31 "F.CrtYd" user "Package Geometry/Place Bound Top")
		(29 "B.CrtYd" user "Package Geometry/Place Bound Bottom")
		(35 "F.Fab" user "Ref Des/Assembly Top")
		(33 "B.Fab" user "Ref Des/Assembly Bottom")
	)
	(footprint ""
		(layer "B.Cu")
		(at 323.386958 -199.980296)
		(property "Reference" "R452"
			(at 0 0 0)
			(layer "B.SilkS")
			(hide yes)
			(effects
				(font
					(size 1.27 1.27)
				)
				(justify mirror)
			)
		)
		(property "Value" ""
			(at 0 0 0)
			(layer "B.Fab")
			(effects
				(font
					(size 1.27 1.27)
				)
				(justify mirror)
			)
		)
		(duplicate_pad_numbers_are_jumpers no)
		(fp_line
			(start -0.7874 -0.4064)
			(end -0.7874 0.4064)
			(stroke
				(width 0.1524)
				(type default)
			)
			(layer "B.SilkS")
		)
		(fp_line
			(start -0.7874 0.4064)
			(end 0.7874 0.4064)
			(stroke
				(width 0.1524)
				(type default)
			)
			(layer "B.SilkS")
		)
		(fp_line
			(start 0.7874 -0.4064)
			(end -0.7874 -0.4064)
			(stroke
				(width 0.1524)
				(type default)
			)
			(layer "B.SilkS")
		)
		(fp_line
			(start 0.7874 0.4064)
			(end 0.7874 -0.4064)
			(stroke
				(width 0.1524)
				(type default)
			)
			(layer "B.SilkS")
		)
		(fp_line
			(start -0.67945 -0.3048)
			(end -0.67945 0.3048)
			(stroke
				(width 0.1)
				(type default)
			)
			(layer "B.Fab")
		)
		(fp_line
			(start -0.67945 0.3048)
			(end -0.120396 0.3048)
			(stroke
				(width 0.1)
				(type default)
			)
			(layer "B.Fab")
		)
		(fp_line
			(start -0.12065 -0.3048)
			(end -0.67945 -0.3048)
			(stroke
				(width 0.1)
				(type default)
			)
			(layer "B.Fab")
		)
		(fp_line
			(start -0.12065 -0.2794)
			(end -0.12065 -0.3048)
			(stroke
				(width 0.1)
				(type default)
			)
			(layer "B.Fab")
		)
		(fp_line
			(start -0.120396 0.2794)
			(end 0.12065 0.2794)
			(stroke
				(width 0.1)
				(type default)
			)
			(layer "B.Fab")
		)
		(fp_line
			(start -0.120396 0.3048)
			(end -0.120396 0.2794)
			(stroke
				(width 0.1)
				(type default)
			)
			(layer "B.Fab")
		)
		(fp_line
			(start 0.12065 -0.305054)
			(end 0.12065 -0.2794)
			(stroke
				(width 0.1)
				(type default)
			)
			(layer "B.Fab")
		)
		(fp_line
			(start 0.12065 -0.2794)
			(end -0.12065 -0.2794)
			(stroke
				(width 0.1)
				(type default)
			)
			(layer "B.Fab")
		)
		(fp_line
			(start 0.12065 0.2794)
			(end 0.12065 0.3048)
			(stroke
				(width 0.1)
				(type default)
			)
			(layer "B.Fab")
		)
		(fp_line
			(start 0.12065 0.3048)
			(end 0.67945 0.3048)
			(stroke
				(width 0.1)
				(type default)
			)
			(layer "B.Fab")
		)
		(fp_line
			(start 0.67945 -0.305054)
			(end 0.12065 -0.305054)
			(stroke
				(width 0.1)
				(type default)
			)
			(layer "B.Fab")
		)
		(fp_line
			(start 0.67945 0.3048)
			(end 0.67945 -0.305054)
			(stroke
				(width 0.1)
				(type default)
			)
			(layer "B.Fab")
		)
		(pad "1" smd circle
			(at 0.40005 0 180)
			(size 0 0)
			(layers "B.Cu" "B.Mask" "B.Paste")
			(net "CPU0_NV_SAVE_N")
		)
		(pad "2" smd circle
			(at -0.40005 0 180)
			(size 0 0)
			(layers "B.Cu" "B.Mask" "B.Paste")
			(net "PVDD18_S5_P0")
		)
	)
	(footprint ""
		(layer "B.Cu")
		(at 421.486076 -362.44403)
		(property "Reference" "PR3"
			(at 0 0 0)
			(layer "B.SilkS")
			(hide yes)
			(effects
				(font
					(size 1.27 1.27)
				)
				(justify mirror)
			)
		)
		(property "Value" ""
			(at 0 0 0)
			(layer "B.Fab")
			(effects
				(font
					(size 1.27 1.27)
				)
				(justify mirror)
			)
		)
		(duplicate_pad_numbers_are_jumpers no)
		(fp_line
			(start -0.7874 -0.4064)
			(end -0.7874 0.4064)
			(stroke
				(width 0.1524)
				(type default)
			)
			(layer "B.SilkS")
		)
		(fp_line
			(start -0.7874 0.4064)
			(end 0.7874 0.4064)
			(stroke
				(width 0.1524)
				(type default)
			)
			(layer "B.SilkS")
		)
		(fp_line
			(start 0.7874 -0.4064)
			(end -0.7874 -0.4064)
			(stroke
				(width 0.1524)
				(type default)
			)
			(layer "B.SilkS")
		)
		(fp_line
			(start 0.7874 0.4064)
			(end 0.7874 -0.4064)
			(stroke
				(width 0.1524)
				(type default)
			)
			(layer "B.SilkS")
		)
		(fp_line
			(start -0.67945 -0.3048)
			(end -0.67945 0.3048)
			(stroke
				(width 0.1)
				(type default)
			)
			(layer "B.Fab")
		)
		(fp_line
			(start -0.67945 0.3048)
			(end -0.120396 0.3048)
			(stroke
				(width 0.1)
				(type default)
			)
			(layer "B.Fab")
		)
		(fp_line
			(start -0.12065 -0.3048)
			(end -0.67945 -0.3048)
			(stroke
				(width 0.1)
				(type default)
			)
			(layer "B.Fab")
		)
		(fp_line
			(start -0.12065 -0.2794)
			(end -0.12065 -0.3048)
			(stroke
				(width 0.1)
				(type default)
			)
			(layer "B.Fab")
		)
		(fp_line
			(start -0.120396 0.2794)
			(end 0.12065 0.2794)
			(stroke
				(width 0.1)
				(type default)
			)
			(layer "B.Fab")
		)
		(fp_line
			(start -0.120396 0.3048)
			(end -0.120396 0.2794)
			(stroke
				(width 0.1)
				(type default)
			)
			(layer "B.Fab")
		)
		(fp_line
			(start 0.12065 -0.305054)
			(end 0.12065 -0.2794)
			(stroke
				(width 0.1)
				(type default)
			)
			(layer "B.Fab")
		)
		(fp_line
			(start 0.12065 -0.2794)
			(end -0.12065 -0.2794)
			(stroke
				(width 0.1)
				(type default)
			)
			(layer "B.Fab")
		)
		(fp_line
			(start 0.12065 0.2794)
			(end 0.12065 0.3048)
			(stroke
				(width 0.1)
				(type default)
			)
			(layer "B.Fab")
		)
		(fp_line
			(start 0.12065 0.3048)
			(end 0.67945 0.3048)
			(stroke
				(width 0.1)
				(type default)
			)
			(layer "B.Fab")
		)
		(fp_line
			(start 0.67945 -0.305054)
			(end 0.12065 -0.305054)
			(stroke
				(width 0.1)
				(type default)
			)
			(layer "B.Fab")
		)
		(fp_line
			(start 0.67945 0.3048)
			(end 0.67945 -0.305054)
			(stroke
				(width 0.1)
				(type default)
			)
			(layer "B.Fab")
		)
		(pad "1" smd circle
			(at 0.40005 0 180)
			(size 0 0)
			(layers "B.Cu" "B.Mask" "B.Paste")
			(net "PVDD11_S3_P0_VMON")
		)
		(pad "2" smd circle
			(at -0.40005 0 180)
			(size 0 0)
			(layers "B.Cu" "B.Mask" "B.Paste")
			(net "GND")
		)
	)
)
